# T6G (Grand Teton) — schematic netlist excerpt (pin names and nets, part order shuffled) for the footprints in the layout excerpt that follows; sources: Cadence DE-HDL packaged netlist, KiCad conversion of 04192023_DAF0TMB3IC0_F0TG_MB_C_brd_V02_OCP.brd

C6547  Q_CAP_DIFFBUS  DIFF BUS_0.22UF 6.3V 20% X6S  pkg C0201  page 286 : \1\ = P5E_CPU0_P1_TX_BUF_C_DP<7> ; \2\ = P5E_CPU0_P1_TX_BUF_DP<7>
R6506  Q_RES  33 5% CHIP  pkg 0402LF  page 360 : A = PWRGD_P1V8_RETIMER_CPU0 ; B = FM_PWRGD_P1V8_RETIMER_CPU0
R6002  Q_RES  0 5% CHIP  pkg 0402LF  page 150 : A = I3C_SCM_1_SCL ; B = I3C_SCM_1_R_SCL

(kicad_pcb
	(version 20260206)
	(generator "pcbnew")
	(generator_version "10.0")
	(general
		(thickness 1.6)
		(legacy_teardrops no)
	)
	(paper "A4")
	(title_block
		(title "04192023_DAF0TMB3IC0_F0TG_MB_C_brd_V02_OCP.brd")
		(comment 1 "Grand Teton / footprints 6530-6532 of 8354")
	)
	(layers
		(0 "F.Cu" signal "TOP")
		(4 "In1.Cu" signal "GND")
		(6 "In2.Cu" signal "IN1")
		(8 "In3.Cu" signal "GND1")
		(10 "In4.Cu" signal "IN2")
		(12 "In5.Cu" signal "GND2")
		(14 "In6.Cu" signal "IN3")
		(16 "In7.Cu" signal "GND3")
		(18 "In8.Cu" signal "VCC")
		(20 "In9.Cu" signal "VCC1")
		(22 "In10.Cu" signal "GND4")
		(24 "In11.Cu" signal "IN4")
		(26 "In12.Cu" signal "GND5")
		(28 "In13.Cu" signal "IN5")
		(30 "In14.Cu" signal "GND6")
		(32 "In15.Cu" signal "IN6")
		(34 "In16.Cu" signal "GND7")
		(2 "B.Cu" signal "BOTTOM")
		(9 "F.Adhes" user "F.Adhesive")
		(11 "B.Adhes" user "B.Adhesive")
		(13 "F.Paste" user "Package Geometry/Pastemask Top")
		(15 "B.Paste" user "Package Geometry/Pastemask Bottom")
		(5 "F.SilkS" user "Ref Des/Silkscreen Top")
		(7 "B.SilkS" user "Ref Des/Silkscreen Bottom")
		(1 "F.Mask" user "Board Geometry/Soldermask Top")
		(3 "B.Mask" user "Board Geometry/Soldermask Bottom")
		(17 "Dwgs.User" user "User.Drawings")
		(19 "Cmts.User" user "User.Comments")
		(21 "Eco1.User" user "User.Eco1")
		(23 "Eco2.User" user "User.Eco2")
		(25 "Edge.Cuts" user "Board Geometry/Outline")
		(27 "Margin" user)
		(31 "F.CrtYd" user "Package Geometry/Place Bound Top")
		(29 "B.CrtYd" user "Package Geometry/Place Bound Bottom")
		(35 "F.Fab" user "Ref Des/Assembly Top")
		(33 "B.Fab" user "Ref Des/Assembly Bottom")
	)
	(footprint ""
		(layer "B.Cu")
		(at 188.310012 -13.60043 -90)
		(property "Reference" "R6002"
			(at 0 0 90)
			(layer "B.SilkS")
			(hide yes)
			(effects
				(font
					(size 1.27 1.27)
				)
				(justify mirror)
			)
		)
		(property "Value" ""
			(at 0 0 90)
			(layer "B.Fab")
			(effects
				(font
					(size 1.27 1.27)
				)
				(justify mirror)
			)
		)
		(duplicate_pad_numbers_are_jumpers no)
		(fp_line
			(start -0.7874 0.4064)
			(end 0.7874 0.4064)
			(stroke
				(width 0.1524)
				(type default)
			)
			(layer "B.SilkS")
		)
		(fp_line
			(start 0.7874 0.4064)
			(end 0.7874 -0.4064)
			(stroke
				(width 0.1524)
				(type default)
			)
			(layer "B.SilkS")
		)
		(fp_line
			(start -0.7874 -0.4064)
			(end -0.7874 0.4064)
			(stroke
				(width 0.1524)
				(type default)
			)
			(layer "B.SilkS")
		)
		(fp_line
			(start 0.7874 -0.4064)
			(end -0.7874 -0.4064)
			(stroke
				(width 0.1524)
				(type default)
			)
			(layer "B.SilkS")
		)
		(fp_line
			(start -0.67945 0.3048)
			(end -0.120396 0.3048)
			(stroke
				(width 0.1)
				(type default)
			)
			(layer "B.Fab")
		)
		(fp_line
			(start -0.120396 0.3048)
			(end -0.120396 0.2794)
			(stroke
				(width 0.1)
				(type default)
			)
			(layer "B.Fab")
		)
		(fp_line
			(start 0.12065 0.3048)
			(end 0.67945 0.3048)
			(stroke
				(width 0.1)
				(type default)
			)
			(layer "B.Fab")
		)
		(fp_line
			(start 0.67945 0.3048)
			(end 0.67945 -0.305054)
			(stroke
				(width 0.1)
				(type default)
			)
			(layer "B.Fab")
		)
		(fp_line
			(start -0.120396 0.2794)
			(end 0.12065 0.2794)
			(stroke
				(width 0.1)
				(type default)
			)
			(layer "B.Fab")
		)
		(fp_line
			(start 0.12065 0.2794)
			(end 0.12065 0.3048)
			(stroke
				(width 0.1)
				(type default)
			)
			(layer "B.Fab")
		)
		(fp_line
			(start -0.12065 -0.2794)
			(end -0.12065 -0.3048)
			(stroke
				(width 0.1)
				(type default)
			)
			(layer "B.Fab")
		)
		(fp_line
			(start 0.12065 -0.2794)
			(end -0.12065 -0.2794)
			(stroke
				(width 0.1)
				(type default)
			)
			(layer "B.Fab")
		)
		(fp_line
			(start -0.67945 -0.3048)
			(end -0.67945 0.3048)
			(stroke
				(width 0.1)
				(type default)
			)
			(layer "B.Fab")
		)
		(fp_line
			(start -0.12065 -0.3048)
			(end -0.67945 -0.3048)
			(stroke
				(width 0.1)
				(type default)
			)
			(layer "B.Fab")
		)
		(fp_line
			(start 0.12065 -0.305054)
			(end 0.12065 -0.2794)
			(stroke
				(width 0.1)
				(type default)
			)
			(layer "B.Fab")
		)
		(fp_line
			(start 0.67945 -0.305054)
			(end 0.12065 -0.305054)
			(stroke
				(width 0.1)
				(type default)
			)
			(layer "B.Fab")
		)
		(pad "1" smd circle
			(at 0.40005 0 90)
			(size 0 0)
			(layers "B.Cu" "B.Mask" "B.Paste")
			(net "I3C_SCM_1_SCL")
		)
		(pad "2" smd circle
			(at -0.40005 0 90)
			(size 0 0)
			(layers "B.Cu" "B.Mask" "B.Paste")
			(net "I3C_SCM_1_R_SCL")
		)
	)
	(footprint ""
		(layer "B.Cu")
		(at 240.469928 -289.066732 90)
		(property "Reference" "R6506"
			(at 0 0 90)
			(layer "B.SilkS")
			(hide yes)
			(effects
				(font
					(size 1.27 1.27)
				)
				(justify mirror)
			)
		)
		(property "Value" ""
			(at 0 0 90)
			(layer "B.Fab")
			(effects
				(font
					(size 1.27 1.27)
				)
				(justify mirror)
			)
		)
		(duplicate_pad_numbers_are_jumpers no)
		(fp_line
			(start 0.7874 -0.4064)
			(end -0.7874 -0.4064)
			(stroke
				(width 0.1524)
				(type default)
			)
			(layer "B.SilkS")
		)
		(fp_line
			(start -0.7874 -0.4064)
			(end -0.7874 0.4064)
			(stroke
				(width 0.1524)
				(type default)
			)
			(layer "B.SilkS")
		)
		(fp_line
			(start 0.7874 0.4064)
			(end 0.7874 -0.4064)
			(stroke
				(width 0.1524)
				(type default)
			)
			(layer "B.SilkS")
		)
		(fp_line
			(start -0.7874 0.4064)
			(end 0.7874 0.4064)
			(stroke
				(width 0.1524)
				(type default)
			)
			(layer "B.SilkS")
		)
		(fp_line
			(start 0.67945 -0.305054)
			(end 0.12065 -0.305054)
			(stroke
				(width 0.1)
				(type default)
			)
			(layer "B.Fab")
		)
		(fp_line
			(start 0.12065 -0.305054)
			(end 0.12065 -0.2794)
			(stroke
				(width 0.1)
				(type default)
			)
			(layer "B.Fab")
		)
		(fp_line
			(start -0.12065 -0.3048)
			(end -0.67945 -0.3048)
			(stroke
				(width 0.1)
				(type default)
			)
			(layer "B.Fab")
		)
		(fp_line
			(start -0.67945 -0.3048)
			(end -0.67945 0.3048)
			(stroke
				(width 0.1)
				(type default)
			)
			(layer "B.Fab")
		)
		(fp_line
			(start 0.12065 -0.2794)
			(end -0.12065 -0.2794)
			(stroke
				(width 0.1)
				(type default)
			)
			(layer "B.Fab")
		)
		(fp_line
			(start -0.12065 -0.2794)
			(end -0.12065 -0.3048)
			(stroke
				(width 0.1)
				(type default)
			)
			(layer "B.Fab")
		)
		(fp_line
			(start 0.12065 0.2794)
			(end 0.12065 0.3048)
			(stroke
				(width 0.1)
				(type default)
			)
			(layer "B.Fab")
		)
		(fp_line
			(start -0.120396 0.2794)
			(end 0.12065 0.2794)
			(stroke
				(width 0.1)
				(type default)
			)
			(layer "B.Fab")
		)
		(fp_line
			(start 0.67945 0.3048)
			(end 0.67945 -0.305054)
			(stroke
				(width 0.1)
				(type default)
			)
			(layer "B.Fab")
		)
		(fp_line
			(start 0.12065 0.3048)
			(end 0.67945 0.3048)
			(stroke
				(width 0.1)
				(type default)
			)
			(layer "B.Fab")
		)
		(fp_line
			(start -0.120396 0.3048)
			(end -0.120396 0.2794)
			(stroke
				(width 0.1)
				(type default)
			)
			(layer "B.Fab")
		)
		(fp_line
			(start -0.67945 0.3048)
			(end -0.120396 0.3048)
			(stroke
				(width 0.1)
				(type default)
			)
			(layer "B.Fab")
		)
		(pad "1" smd circle
			(at 0.40005 0 270)
			(size 0 0)
			(layers "B.Cu" "B.Mask" "B.Paste")
			(net "PWRGD_P1V8_RETIMER_CPU0")
		)
		(pad "2" smd circle
			(at -0.40005 0 270)
			(size 0 0)
			(layers "B.Cu" "B.Mask" "B.Paste")
			(net "FM_PWRGD_P1V8_RETIMER_CPU0")
		)
	)
	(footprint ""
		(layer "B.Cu")
		(at 327.657206 -416.899344 90)
		(property "Reference" "C6547"
			(at 0 0 90)
			(layer "B.SilkS")
			(hide yes)
			(effects
				(font
					(size 1.27 1.27)
				)
				(justify mirror)
			)
		)
		(property "Value" ""
			(at 0 0 90)
			(layer "B.Fab")
			(effects
				(font
					(size 1.27 1.27)
				)
				(justify mirror)
			)
		)
		(duplicate_pad_numbers_are_jumpers no)
		(fp_line
			(start 0.299974 -0.150114)
			(end -0.299974 -0.150114)
			(stroke
				(width 0.1)
				(type default)
			)
			(layer "B.Fab")
		)
		(fp_line
			(start -0.299974 -0.150114)
			(end -0.299974 0.150114)
			(stroke
				(width 0.1)
				(type default)
			)
			(layer "B.Fab")
		)
		(fp_line
			(start 0.299974 0.150114)
			(end 0.299974 -0.150114)
			(stroke
				(width 0.1)
				(type default)
			)
			(layer "B.Fab")
		)
		(fp_line
			(start -0.299974 0.150114)
			(end 0.299974 0.150114)
			(stroke
				(width 0.1)
				(type default)
			)
			(layer "B.Fab")
		)
		(pad "1" smd rect
			(at 0.2667 0 270)
			(size 0.3048 0.381)
			(layers "B.Cu" "B.Mask" "B.Paste")
			(net "P5E_CPU0_P1_TX_BUF_C_DP<7>")
		)
		(pad "2" smd rect
			(at -0.2667 0 270)
			(size 0.3048 0.381)
			(layers "B.Cu" "B.Mask" "B.Paste")
			(net "P5E_CPU0_P1_TX_BUF_DP<7>")
		)
	)
)
